FILE_TYPE = MULTI_PHYS_TABLE;

PART 'CONN10_HBC1051L300D8H'

{========================================================================================}
:VALUE                     | PART_TYPE | MATERIAL | PART_NUMBER    = STANDARD        | LIFECYCLE      | PART_NUMBER   | JEDEC_TYPE    | DESCRIPTION                               | MANUFTR | MANUF_PN           | RD_CMPLS_LVL | CMPLS_LVL | CLASS | DIP_SMD | FROM_PJ     | DATA                       | FP_ECN | EE_CHECK_LIST | CREATOR | CREATEDAY  | PSL | STATUS | ESD_CDM | ESD_HBM | ESD_MM | MSD  | PIN_LENGTH_LONG_PIN | PIN_LENGTH_SHORT_PIN ;
{========================================================================================}
 'CONN10_HBC1051-L300D-8H' | 'THLF'    | 'IO'     | 'DFHD10MS117'(!) = ''               | ''               | 'DFHD10MS117' |'HEADER2X5XJ'| 'CONN DIP HEADER 10P 2R MS(P2.54, H8.38)' | 'FOX'   | 'HBC1051-L300D-8H' | 'EP(V1)'     | 'EP(V1)'  | 'IO'  | 'DIP'   | 'S3IS-MARK' | 'FOX_HBC1051-L300D-8H.pdf' | ''     | ''            | ''      | '20210203' | ''  | ''     | '0'     | '0'     | '0'    | 'NA' | '126 MILS'          | '126 MILS'          
 'CONN10_HBC1051-L300D-8H' | 'THLF'    | 'EMPTY'  | 'DFHD10MS117'(!) = ''               | ''               | 'DFHD10MS117' |'HEADER2X5XJ'| 'CONN DIP HEADER 10P 2R MS(P2.54, H8.38)' | 'FOX'   | 'HBC1051-L300D-8H' | 'EP(V1)'     | 'EP(V1)'  | 'IO'  | 'DIP'   | 'S3IS-MARK' | 'FOX_HBC1051-L300D-8H.pdf' | ''     | ''            | ''      | '20210203' | ''  | ''     | '0'     | '0'     | '0'    | 'NA' | '126 MILS'          | '126 MILS'          

END_PART

END.

